# BASEBOARD_FAB2 (Tioga Pass) — schematic netlist excerpt (pin names and nets, part order shuffled) for the footprints in the layout excerpt that follows; sources: Cadence DE-HDL packaged netlist, KiCad conversion of Wiwynn_Tioga_Pass_MB.brd

R9R4  RES  10.0 1% CHIP  pkg 0402  page 200 : A = A_HSC_GATE ; B = A_HSC_GATE2_R
R1T7  RES  20.0 1% CHIP  pkg 0402  page 160 : A = SMB_SLOTX24_STBY_LVC3_SCL_R ; B = SMB_SLOTX24_BMC_STBY_LVC3_SCL
R12W7  665KR5B-1-GP  0.1%  pkg SMD-RG3  page 197 : \1\ = P12V_NVDIMM_DEF_D ; \2\ = VR_PVDDQ_DEF_VINSEN

(kicad_pcb
	(version 20260206)
	(generator "pcbnew")
	(generator_version "10.0")
	(general
		(thickness 1.6)
		(legacy_teardrops no)
	)
	(paper "A4")
	(title_block
		(title "Wiwynn_Tioga_Pass_MB.brd")
		(comment 1 "Tioga Pass / footprints 3622-3624 of 4770")
	)
	(layers
		(0 "F.Cu" signal "TOP")
		(4 "In1.Cu" signal "L2GND")
		(6 "In2.Cu" signal "L3")
		(8 "In3.Cu" signal "L4GND")
		(10 "In4.Cu" signal "L5")
		(12 "In5.Cu" signal "L6GND")
		(14 "In6.Cu" signal "L7VCC")
		(16 "In7.Cu" signal "L8VCC")
		(18 "In8.Cu" signal "L9GND")
		(20 "In9.Cu" signal "L10")
		(22 "In10.Cu" signal "L11GND")
		(24 "In11.Cu" signal "L12")
		(26 "In12.Cu" signal "L13GND")
		(2 "B.Cu" signal "BOTTOM")
		(9 "F.Adhes" user "F.Adhesive")
		(11 "B.Adhes" user "B.Adhesive")
		(13 "F.Paste" user "Package Geometry/Pastemask Top")
		(15 "B.Paste" user "Package Geometry/Pastemask Bottom")
		(5 "F.SilkS" user "Ref Des/Silkscreen Top")
		(7 "B.SilkS" user "Ref Des/Silkscreen Bottom")
		(1 "F.Mask" user "Board Geometry/Soldermask Top")
		(3 "B.Mask" user "Board Geometry/Soldermask Bottom")
		(17 "Dwgs.User" user "User.Drawings")
		(19 "Cmts.User" user "User.Comments")
		(21 "Eco1.User" user "User.Eco1")
		(23 "Eco2.User" user "User.Eco2")
		(25 "Edge.Cuts" user "Board Geometry/Outline")
		(27 "Margin" user)
		(31 "F.CrtYd" user "Package Geometry/Place Bound Top")
		(29 "B.CrtYd" user "Package Geometry/Place Bound Bottom")
		(35 "F.Fab" user "Ref Des/Assembly Top")
		(33 "B.Fab" user "Ref Des/Assembly Bottom")
	)
	(footprint ""
		(layer "B.Cu")
		(at 417.8173 -48.9204 90)
		(property "Reference" "R1T7"
			(at 0 0 90)
			(layer "B.SilkS")
			(hide yes)
			(effects
				(font
					(size 1.27 1.27)
				)
				(justify mirror)
			)
		)
		(property "Value" ""
			(at 0 0 90)
			(layer "B.Fab")
			(effects
				(font
					(size 1.27 1.27)
				)
				(justify mirror)
			)
		)
		(duplicate_pad_numbers_are_jumpers no)
		(fp_poly
			(pts
				(xy 0.2794 -0.1016) (xy -0.2794 -0.1016) (xy -0.2794 0.9906) (xy 0.2794 0.9906)
			)
			(stroke
				(width 0)
				(type default)
			)
			(fill no)
			(layer "B.CrtYd")
		)
		(fp_line
			(start 0.2794 -0.1016)
			(end 0.2794 0.9906)
			(stroke
				(width 0.1)
				(type default)
			)
			(layer "B.Fab")
		)
		(fp_line
			(start -0.2794 -0.1016)
			(end 0.2794 -0.1016)
			(stroke
				(width 0.1)
				(type default)
			)
			(layer "B.Fab")
		)
		(fp_line
			(start 0.2794 0.9906)
			(end -0.2794 0.9906)
			(stroke
				(width 0.1)
				(type default)
			)
			(layer "B.Fab")
		)
		(fp_line
			(start -0.2794 0.9906)
			(end -0.2794 -0.1016)
			(stroke
				(width 0.1)
				(type default)
			)
			(layer "B.Fab")
		)
		(pad "1" smd rect
			(at 0 0 270)
			(size 0.508 0.508)
			(layers "B.Cu" "B.Mask" "B.Paste")
			(net "SMB_SLOTX24_STBY_LVC3_SCL_R")
		)
		(pad "2" smd rect
			(at 0 0.889 270)
			(size 0.508 0.508)
			(layers "B.Cu" "B.Mask" "B.Paste")
			(net "SMB_SLOTX24_BMC_STBY_LVC3_SCL")
		)
		(zone
			(layer "B.Cu")
			(hatch none 0.5)
			(connect_pads
				(clearance 0)
			)
			(min_thickness 0.25)
			(keepout
				(tracks allowed)
				(vias not_allowed)
				(pads allowed)
				(copperpour not_allowed)
				(footprints allowed)
			)
			(placement
				(enabled no)
				(sheetname "")
			)
			(fill
				(thermal_gap 0.5)
				(thermal_bridge_width 0.5)
				(island_removal_mode 0)
			)
			(polygon
				(pts
					(xy 418.0713 -49.1744) (xy 418.0713 -48.6664) (xy 418.4523 -48.6664) (xy 418.4523 -49.1744)
				)
			)
		)
		(zone
			(layer "B.Cu")
			(hatch none 0.5)
			(connect_pads
				(clearance 0)
			)
			(min_thickness 0.25)
			(keepout
				(tracks not_allowed)
				(vias allowed)
				(pads allowed)
				(copperpour not_allowed)
				(footprints allowed)
			)
			(placement
				(enabled no)
				(sheetname "")
			)
			(fill
				(thermal_gap 0.5)
				(thermal_bridge_width 0.5)
				(island_removal_mode 0)
			)
			(polygon
				(pts
					(xy 418.4523 -49.1744) (xy 418.4523 -48.6664) (xy 418.0713 -48.6664) (xy 418.0713 -49.1744)
				)
			)
		)
	)
	(footprint ""
		(layer "B.Cu")
		(at 24.638 -56.8452 -90)
		(property "Reference" "R9R4"
			(at 0 0 90)
			(layer "B.SilkS")
			(hide yes)
			(effects
				(font
					(size 1.27 1.27)
				)
				(justify mirror)
			)
		)
		(property "Value" ""
			(at 0 0 90)
			(layer "B.Fab")
			(effects
				(font
					(size 1.27 1.27)
				)
				(justify mirror)
			)
		)
		(duplicate_pad_numbers_are_jumpers no)
		(fp_rect
			(start 0.2794 0.9906)
			(end -0.2794 -0.1016)
			(stroke
				(width 0)
				(type default)
			)
			(fill no)
			(layer "B.CrtYd")
		)
		(fp_line
			(start -0.2794 0.9906)
			(end -0.2794 -0.1016)
			(stroke
				(width 0.1)
				(type default)
			)
			(layer "B.Fab")
		)
		(fp_line
			(start 0.2794 0.9906)
			(end -0.2794 0.9906)
			(stroke
				(width 0.1)
				(type default)
			)
			(layer "B.Fab")
		)
		(fp_line
			(start -0.2794 -0.1016)
			(end 0.2794 -0.1016)
			(stroke
				(width 0.1)
				(type default)
			)
			(layer "B.Fab")
		)
		(fp_line
			(start 0.2794 -0.1016)
			(end 0.2794 0.9906)
			(stroke
				(width 0.1)
				(type default)
			)
			(layer "B.Fab")
		)
		(pad "1" smd rect
			(at 0 0 90)
			(size 0.508 0.508)
			(layers "B.Cu" "B.Mask" "B.Paste")
			(net "A_HSC_GATE")
		)
		(pad "2" smd rect
			(at 0 0.889 90)
			(size 0.508 0.508)
			(layers "B.Cu" "B.Mask" "B.Paste")
			(net "A_HSC_GATE2_R")
		)
		(zone
			(layer "B.Cu")
			(hatch none 0.5)
			(connect_pads
				(clearance 0)
			)
			(min_thickness 0.25)
			(keepout
				(tracks not_allowed)
				(vias allowed)
				(pads allowed)
				(copperpour not_allowed)
				(footprints allowed)
			)
			(placement
				(enabled no)
				(sheetname "")
			)
			(fill
				(thermal_gap 0.5)
				(thermal_bridge_width 0.5)
				(island_removal_mode 0)
			)
			(polygon
				(pts
					(xy 24.003 -56.5912) (xy 24.384 -56.5912) (xy 24.384 -57.0992) (xy 24.003 -57.0992)
				)
			)
		)
		(zone
			(layer "B.Cu")
			(hatch none 0.5)
			(connect_pads
				(clearance 0)
			)
			(min_thickness 0.25)
			(keepout
				(tracks allowed)
				(vias not_allowed)
				(pads allowed)
				(copperpour not_allowed)
				(footprints allowed)
			)
			(placement
				(enabled no)
				(sheetname "")
			)
			(fill
				(thermal_gap 0.5)
				(thermal_bridge_width 0.5)
				(island_removal_mode 0)
			)
			(polygon
				(pts
					(xy 24.003 -56.5912) (xy 24.384 -56.5912) (xy 24.384 -57.0992) (xy 24.003 -57.0992)
				)
			)
		)
	)
	(footprint ""
		(layer "B.Cu")
		(at 355.514148 -137.904728 -90)
		(property "Reference" "R12W7"
			(at 0 0 90)
			(layer "B.SilkS")
			(hide yes)
			(effects
				(font
					(size 1.27 1.27)
				)
				(justify mirror)
			)
		)
		(property "Value" "*"
			(at 0 -8.9535 270)
			(unlocked yes)
			(layer "B.Fab")
			(hide yes)
			(effects
				(font
					(size 1.27 1.016)
					(thickness 0.1524)
				)
				(justify mirror)
			)
		)
		(property "Device Type" "665KR5B-1-GP_SMD-RG3-665KR5B-1A"
			(at 0 -10.6299 270)
			(unlocked yes)
			(layer "B.Fab")
			(hide yes)
			(effects
				(font
					(size 1.27 1.016)
					(thickness 0.1524)
				)
				(justify mirror)
			)
		)
		(duplicate_pad_numbers_are_jumpers no)
		(fp_line
			(start -0.889 1.7018)
			(end -0.889 -0.508)
			(stroke
				(width 0.1524)
				(type default)
			)
			(layer "B.SilkS")
		)
		(fp_line
			(start 0.889 1.7018)
			(end -0.889 1.7018)
			(stroke
				(width 0.1524)
				(type default)
			)
			(layer "B.SilkS")
		)
		(fp_line
			(start 0.889 0.0762)
			(end 0.889 1.7018)
			(stroke
				(width 0.1524)
				(type default)
			)
			(layer "B.SilkS")
		)
		(fp_line
			(start -0.889 -1.7018)
			(end -0.889 -0.381)
			(stroke
				(width 0.1524)
				(type default)
			)
			(layer "B.SilkS")
		)
		(fp_line
			(start -0.889 -1.7018)
			(end 0.889 -1.7018)
			(stroke
				(width 0.1524)
				(type default)
			)
			(layer "B.SilkS")
		)
		(fp_line
			(start 0.889 -1.7018)
			(end 0.889 0.2794)
			(stroke
				(width 0.1524)
				(type default)
			)
			(layer "B.SilkS")
		)
		(fp_poly
			(pts
				(xy -0.9652 -1.778) (xy -0.9652 1.778) (xy 0.9652 1.778) (xy 0.9652 -1.778)
			)
			(stroke
				(width 0)
				(type default)
			)
			(fill no)
			(layer "B.CrtYd")
		)
		(fp_rect
			(start 0.9652 1.778)
			(end -0.9652 -1.778)
			(stroke
				(width 0)
				(type default)
			)
			(fill no)
			(layer "B.Fab")
		)
		(pad "1" smd rect
			(at 0 -0.9652 90)
			(size 1.397 1.143)
			(layers "B.Cu" "B.Mask" "B.Paste")
			(net "P12V_NVDIMM_DEF_D")
		)
		(pad "2" smd rect
			(at 0 0.9652 90)
			(size 1.397 1.143)
			(layers "B.Cu" "B.Mask" "B.Paste")
			(net "VR_PVDDQ_DEF_VINSEN")
		)
	)
)
